(kicad_pcb
	(version 20260206)
	(generator "pcbnew")
	(generator_version "10.0")
	(general
		(thickness 1.6)
		(legacy_teardrops no)
	)
	(paper "A4")
	(title_block
		(title "12092022_DA0F0TFB6D0_F0T_FAN_BOARD_MP5048_D_brd_v02_OCP.brd")
		(comment 1 "Grand Teton / footprints 584-590 of 924")
	)
	(layers
		(0 "F.Cu" signal "TOP")
		(4 "In1.Cu" signal "GND")
		(6 "In2.Cu" signal "IN1")
		(8 "In3.Cu" signal "IN2")
		(10 "In4.Cu" signal "GND1")
		(2 "B.Cu" signal "BOTTOM")
		(9 "F.Adhes" user "F.Adhesive")
		(11 "B.Adhes" user "B.Adhesive")
		(13 "F.Paste" user "Package Geometry/Pastemask Top")
		(15 "B.Paste" user "Package Geometry/Pastemask Bottom")
		(5 "F.SilkS" user "Ref Des/Silkscreen Top")
		(7 "B.SilkS" user "Ref Des/Silkscreen Bottom")
		(1 "F.Mask" user "Board Geometry/Soldermask Top")
		(3 "B.Mask" user "Board Geometry/Soldermask Bottom")
		(17 "Dwgs.User" user "User.Drawings")
		(19 "Cmts.User" user "User.Comments")
		(21 "Eco1.User" user "User.Eco1")
		(23 "Eco2.User" user "User.Eco2")
		(25 "Edge.Cuts" user "Board Geometry/Outline")
		(27 "Margin" user)
		(31 "F.CrtYd" user "Package Geometry/Place Bound Top")
		(29 "B.CrtYd" user "Package Geometry/Place Bound Bottom")
		(35 "F.Fab" user "Ref Des/Assembly Top")
		(33 "B.Fab" user "Ref Des/Assembly Bottom")
	)
	(footprint ""
		(layer "F.Cu")
		(at 33.02 -119.564912)
		(property "Reference" "D279"
			(at 2.032 -1.058418 0)
			(unlocked yes)
			(layer "F.SilkS")
			(effects
				(font
					(size 0.7874 0.5842)
					(thickness 0.1524)
				)
				(justify left)
			)
		)
		(property "Value" ""
			(at 0 0 0)
			(layer "F.Fab")
			(effects
				(font
					(size 1.27 1.27)
				)
			)
		)
		(duplicate_pad_numbers_are_jumpers no)
		(fp_line
			(start -0.854964 -0.450088)
			(end -0.854964 0.450088)
			(stroke
				(width 0.1524)
				(type default)
			)
			(layer "F.SilkS")
		)
		(fp_line
			(start -0.854964 0.450088)
			(end 0.925068 0.450088)
			(stroke
				(width 0.1524)
				(type default)
			)
			(layer "F.SilkS")
		)
		(fp_line
			(start 0.845058 0.4064)
			(end 0.845058 -0.381)
			(stroke
				(width 0.1524)
				(type default)
			)
			(layer "F.SilkS")
		)
		(fp_line
			(start 0.870458 -0.2794)
			(end 0.845058 0.4064)
			(stroke
				(width 0.1524)
				(type default)
			)
			(layer "F.SilkS")
		)
		(fp_line
			(start 0.94488 -0.450088)
			(end -0.854964 -0.450088)
			(stroke
				(width 0.1524)
				(type default)
			)
			(layer "F.SilkS")
		)
		(fp_line
			(start 0.94488 0.450088)
			(end 0.94488 -0.450088)
			(stroke
				(width 0.1524)
				(type default)
			)
			(layer "F.SilkS")
		)
		(fp_line
			(start -0.54991 -0.350012)
			(end -0.54991 0.350012)
			(stroke
				(width 0.1)
				(type default)
			)
			(layer "F.Fab")
		)
		(fp_line
			(start -0.54991 0.350012)
			(end 0.54991 0.350012)
			(stroke
				(width 0.1)
				(type default)
			)
			(layer "F.Fab")
		)
		(fp_line
			(start 0.54991 -0.350012)
			(end -0.54991 -0.350012)
			(stroke
				(width 0.1)
				(type default)
			)
			(layer "F.Fab")
		)
		(fp_line
			(start 0.54991 0.350012)
			(end 0.54991 -0.350012)
			(stroke
				(width 0.1)
				(type default)
			)
			(layer "F.Fab")
		)
		(fp_text user "+"
			(at -0.508 0.915162 180)
			(unlocked yes)
			(layer "F.SilkS")
			(effects
				(font
					(size 1.905 1.4224)
					(thickness 0.1524)
				)
				(justify left)
			)
		)
		(fp_text user "-"
			(at 1.905 0.915162 180)
			(unlocked yes)
			(layer "F.SilkS")
			(effects
				(font
					(size 1.905 1.4224)
					(thickness 0.1524)
				)
				(justify left)
			)
		)
		(fp_text user "+"
			(at -0.808228 0.239014 180)
			(unlocked yes)
			(layer "F.Fab")
			(effects
				(font
					(size 1.905 1.4224)
					(thickness 0.1524)
				)
				(justify left)
			)
		)
		(fp_text user "-"
			(at 2.48539 0.239014 180)
			(unlocked yes)
			(layer "F.Fab")
			(effects
				(font
					(size 1.905 1.4224)
					(thickness 0.1524)
				)
				(justify left)
			)
		)
		(pad "A" smd rect
			(at -0.424942 0)
			(size 0.5588 0.6096)
			(layers "F.Cu" "F.Mask" "F.Paste")
			(net "GND")
		)
		(pad "C" smd rect
			(at 0.424942 0 180)
			(size 0.5588 0.6096)
			(layers "F.Cu" "F.Mask" "F.Paste")
			(net "FAN_2_PWM_OL_R")
		)
	)
	(footprint ""
		(layer "F.Cu")
		(at 33.02 -118.237 180)
		(property "Reference" "R5330"
			(at 0 0 180)
			(layer "F.SilkS")
			(hide yes)
			(effects
				(font
					(size 1.27 1.27)
				)
			)
		)
		(property "Value" ""
			(at 0 0 180)
			(layer "F.Fab")
			(effects
				(font
					(size 1.27 1.27)
				)
			)
		)
		(duplicate_pad_numbers_are_jumpers no)
		(fp_line
			(start 0.7874 0.4064)
			(end -0.7874 0.4064)
			(stroke
				(width 0.1524)
				(type default)
			)
			(layer "F.SilkS")
		)
		(fp_line
			(start 0.7874 -0.4064)
			(end 0.7874 0.4064)
			(stroke
				(width 0.1524)
				(type default)
			)
			(layer "F.SilkS")
		)
		(fp_line
			(start -0.7874 0.4064)
			(end -0.7874 -0.4064)
			(stroke
				(width 0.1524)
				(type default)
			)
			(layer "F.SilkS")
		)
		(fp_line
			(start -0.7874 -0.4064)
			(end 0.7874 -0.4064)
			(stroke
				(width 0.1524)
				(type default)
			)
			(layer "F.SilkS")
		)
		(fp_line
			(start 0.67945 0.3048)
			(end 0.120396 0.3048)
			(stroke
				(width 0.1)
				(type default)
			)
			(layer "F.Fab")
		)
		(fp_line
			(start 0.67945 -0.3048)
			(end 0.67945 0.3048)
			(stroke
				(width 0.1)
				(type default)
			)
			(layer "F.Fab")
		)
		(fp_line
			(start 0.12065 -0.2794)
			(end 0.12065 -0.3048)
			(stroke
				(width 0.1)
				(type default)
			)
			(layer "F.Fab")
		)
		(fp_line
			(start 0.12065 -0.3048)
			(end 0.67945 -0.3048)
			(stroke
				(width 0.1)
				(type default)
			)
			(layer "F.Fab")
		)
		(fp_line
			(start 0.120396 0.3048)
			(end 0.120396 0.2794)
			(stroke
				(width 0.1)
				(type default)
			)
			(layer "F.Fab")
		)
		(fp_line
			(start 0.120396 0.2794)
			(end -0.12065 0.2794)
			(stroke
				(width 0.1)
				(type default)
			)
			(layer "F.Fab")
		)
		(fp_line
			(start -0.12065 0.3048)
			(end -0.67945 0.3048)
			(stroke
				(width 0.1)
				(type default)
			)
			(layer "F.Fab")
		)
		(fp_line
			(start -0.12065 0.2794)
			(end -0.12065 0.3048)
			(stroke
				(width 0.1)
				(type default)
			)
			(layer "F.Fab")
		)
		(fp_line
			(start -0.12065 -0.2794)
			(end 0.12065 -0.2794)
			(stroke
				(width 0.1)
				(type default)
			)
			(layer "F.Fab")
		)
		(fp_line
			(start -0.12065 -0.305054)
			(end -0.12065 -0.2794)
			(stroke
				(width 0.1)
				(type default)
			)
			(layer "F.Fab")
		)
		(fp_line
			(start -0.67945 0.3048)
			(end -0.67945 -0.305054)
			(stroke
				(width 0.1)
				(type default)
			)
			(layer "F.Fab")
		)
		(fp_line
			(start -0.67945 -0.305054)
			(end -0.12065 -0.305054)
			(stroke
				(width 0.1)
				(type default)
			)
			(layer "F.Fab")
		)
		(pad "1" smd rect
			(at -0.40005 0)
			(size 0.4572 0.508)
			(layers "F.Cu" "F.Mask" "F.Paste")
			(net "FAN_2_TACH_IL_R")
		)
		(pad "2" smd rect
			(at 0.40005 0)
			(size 0.4572 0.508)
			(layers "F.Cu" "F.Mask" "F.Paste")
			(net "FAN_2_TACH_IL")
		)
	)
	(footprint ""
		(layer "F.Cu")
		(at 20.5232 -162.941 -90)
		(property "Reference" "R5472"
			(at 0 0 270)
			(layer "F.SilkS")
			(hide yes)
			(effects
				(font
					(size 1.27 1.27)
				)
			)
		)
		(property "Value" ""
			(at 0 0 270)
			(layer "F.Fab")
			(effects
				(font
					(size 1.27 1.27)
				)
			)
		)
		(duplicate_pad_numbers_are_jumpers no)
		(fp_line
			(start -0.7874 0.4064)
			(end -0.7874 -0.4064)
			(stroke
				(width 0.1524)
				(type default)
			)
			(layer "F.SilkS")
		)
		(fp_line
			(start 0.7874 0.4064)
			(end -0.7874 0.4064)
			(stroke
				(width 0.1524)
				(type default)
			)
			(layer "F.SilkS")
		)
		(fp_line
			(start -0.7874 -0.4064)
			(end 0.7874 -0.4064)
			(stroke
				(width 0.1524)
				(type default)
			)
			(layer "F.SilkS")
		)
		(fp_line
			(start 0.7874 -0.4064)
			(end 0.7874 0.4064)
			(stroke
				(width 0.1524)
				(type default)
			)
			(layer "F.SilkS")
		)
		(fp_line
			(start -0.67945 0.3048)
			(end -0.67945 -0.305054)
			(stroke
				(width 0.1)
				(type default)
			)
			(layer "F.Fab")
		)
		(fp_line
			(start -0.12065 0.3048)
			(end -0.67945 0.3048)
			(stroke
				(width 0.1)
				(type default)
			)
			(layer "F.Fab")
		)
		(fp_line
			(start 0.120396 0.3048)
			(end 0.120396 0.2794)
			(stroke
				(width 0.1)
				(type default)
			)
			(layer "F.Fab")
		)
		(fp_line
			(start 0.67945 0.3048)
			(end 0.120396 0.3048)
			(stroke
				(width 0.1)
				(type default)
			)
			(layer "F.Fab")
		)
		(fp_line
			(start -0.12065 0.2794)
			(end -0.12065 0.3048)
			(stroke
				(width 0.1)
				(type default)
			)
			(layer "F.Fab")
		)
		(fp_line
			(start 0.120396 0.2794)
			(end -0.12065 0.2794)
			(stroke
				(width 0.1)
				(type default)
			)
			(layer "F.Fab")
		)
		(fp_line
			(start -0.12065 -0.2794)
			(end 0.12065 -0.2794)
			(stroke
				(width 0.1)
				(type default)
			)
			(layer "F.Fab")
		)
		(fp_line
			(start 0.12065 -0.2794)
			(end 0.12065 -0.3048)
			(stroke
				(width 0.1)
				(type default)
			)
			(layer "F.Fab")
		)
		(fp_line
			(start 0.12065 -0.3048)
			(end 0.67945 -0.3048)
			(stroke
				(width 0.1)
				(type default)
			)
			(layer "F.Fab")
		)
		(fp_line
			(start 0.67945 -0.3048)
			(end 0.67945 0.3048)
			(stroke
				(width 0.1)
				(type default)
			)
			(layer "F.Fab")
		)
		(fp_line
			(start -0.67945 -0.305054)
			(end -0.12065 -0.305054)
			(stroke
				(width 0.1)
				(type default)
			)
			(layer "F.Fab")
		)
		(fp_line
			(start -0.12065 -0.305054)
			(end -0.12065 -0.2794)
			(stroke
				(width 0.1)
				(type default)
			)
			(layer "F.Fab")
		)
		(pad "1" smd circle
			(at -0.40005 0 270)
			(size 0 0)
			(layers "F.Cu" "F.Mask" "F.Paste")
			(net "P3V3_AUX")
		)
		(pad "2" smd circle
			(at 0.40005 0 270)
			(size 0 0)
			(layers "F.Cu" "F.Mask" "F.Paste")
			(net "PD_TCA9548_SML1_U321_A2")
		)
	)
	(footprint ""
		(layer "F.Cu")
		(at 16.764 -300.736 180)
		(property "Reference" "R5533"
			(at 0 0 180)
			(layer "F.SilkS")
			(hide yes)
			(effects
				(font
					(size 1.27 1.27)
				)
			)
		)
		(property "Value" ""
			(at 0 0 180)
			(layer "F.Fab")
			(effects
				(font
					(size 1.27 1.27)
				)
			)
		)
		(duplicate_pad_numbers_are_jumpers no)
		(fp_line
			(start 0.7874 0.4064)
			(end -0.7874 0.4064)
			(stroke
				(width 0.1524)
				(type default)
			)
			(layer "F.SilkS")
		)
		(fp_line
			(start 0.7874 -0.4064)
			(end 0.7874 0.4064)
			(stroke
				(width 0.1524)
				(type default)
			)
			(layer "F.SilkS")
		)
		(fp_line
			(start -0.7874 0.4064)
			(end -0.7874 -0.4064)
			(stroke
				(width 0.1524)
				(type default)
			)
			(layer "F.SilkS")
		)
		(fp_line
			(start -0.7874 -0.4064)
			(end 0.7874 -0.4064)
			(stroke
				(width 0.1524)
				(type default)
			)
			(layer "F.SilkS")
		)
		(fp_line
			(start 0.67945 0.3048)
			(end 0.120396 0.3048)
			(stroke
				(width 0.1)
				(type default)
			)
			(layer "F.Fab")
		)
		(fp_line
			(start 0.67945 -0.3048)
			(end 0.67945 0.3048)
			(stroke
				(width 0.1)
				(type default)
			)
			(layer "F.Fab")
		)
		(fp_line
			(start 0.12065 -0.2794)
			(end 0.12065 -0.3048)
			(stroke
				(width 0.1)
				(type default)
			)
			(layer "F.Fab")
		)
		(fp_line
			(start 0.12065 -0.3048)
			(end 0.67945 -0.3048)
			(stroke
				(width 0.1)
				(type default)
			)
			(layer "F.Fab")
		)
		(fp_line
			(start 0.120396 0.3048)
			(end 0.120396 0.2794)
			(stroke
				(width 0.1)
				(type default)
			)
			(layer "F.Fab")
		)
		(fp_line
			(start 0.120396 0.2794)
			(end -0.12065 0.2794)
			(stroke
				(width 0.1)
				(type default)
			)
			(layer "F.Fab")
		)
		(fp_line
			(start -0.12065 0.3048)
			(end -0.67945 0.3048)
			(stroke
				(width 0.1)
				(type default)
			)
			(layer "F.Fab")
		)
		(fp_line
			(start -0.12065 0.2794)
			(end -0.12065 0.3048)
			(stroke
				(width 0.1)
				(type default)
			)
			(layer "F.Fab")
		)
		(fp_line
			(start -0.12065 -0.2794)
			(end 0.12065 -0.2794)
			(stroke
				(width 0.1)
				(type default)
			)
			(layer "F.Fab")
		)
		(fp_line
			(start -0.12065 -0.305054)
			(end -0.12065 -0.2794)
			(stroke
				(width 0.1)
				(type default)
			)
			(layer "F.Fab")
		)
		(fp_line
			(start -0.67945 0.3048)
			(end -0.67945 -0.305054)
			(stroke
				(width 0.1)
				(type default)
			)
			(layer "F.Fab")
		)
		(fp_line
			(start -0.67945 -0.305054)
			(end -0.12065 -0.305054)
			(stroke
				(width 0.1)
				(type default)
			)
			(layer "F.Fab")
		)
		(pad "1" smd rect
			(at -0.40005 0)
			(size 0.4572 0.508)
			(layers "F.Cu" "F.Mask" "F.Paste")
			(net "P12V_LED_FAN7")
		)
		(pad "2" smd rect
			(at 0.40005 0)
			(size 0.4572 0.508)
			(layers "F.Cu" "F.Mask" "F.Paste")
			(net "FAN_7_OK_LED_R_N")
		)
	)
	(footprint ""
		(layer "F.Cu")
		(at 28.956 -171.577 180)
		(property "Reference" "R5110"
			(at 0 0 180)
			(layer "F.SilkS")
			(hide yes)
			(effects
				(font
					(size 1.27 1.27)
				)
			)
		)
		(property "Value" ""
			(at 0 0 180)
			(layer "F.Fab")
			(effects
				(font
					(size 1.27 1.27)
				)
			)
		)
		(duplicate_pad_numbers_are_jumpers no)
		(fp_line
			(start 0.7874 0.4064)
			(end -0.7874 0.4064)
			(stroke
				(width 0.1524)
				(type default)
			)
			(layer "F.SilkS")
		)
		(fp_line
			(start 0.7874 -0.4064)
			(end 0.7874 0.4064)
			(stroke
				(width 0.1524)
				(type default)
			)
			(layer "F.SilkS")
		)
		(fp_line
			(start -0.7874 0.4064)
			(end -0.7874 -0.4064)
			(stroke
				(width 0.1524)
				(type default)
			)
			(layer "F.SilkS")
		)
		(fp_line
			(start -0.7874 -0.4064)
			(end 0.7874 -0.4064)
			(stroke
				(width 0.1524)
				(type default)
			)
			(layer "F.SilkS")
		)
		(fp_line
			(start 0.67945 0.3048)
			(end 0.120396 0.3048)
			(stroke
				(width 0.1)
				(type default)
			)
			(layer "F.Fab")
		)
		(fp_line
			(start 0.67945 -0.3048)
			(end 0.67945 0.3048)
			(stroke
				(width 0.1)
				(type default)
			)
			(layer "F.Fab")
		)
		(fp_line
			(start 0.12065 -0.2794)
			(end 0.12065 -0.3048)
			(stroke
				(width 0.1)
				(type default)
			)
			(layer "F.Fab")
		)
		(fp_line
			(start 0.12065 -0.3048)
			(end 0.67945 -0.3048)
			(stroke
				(width 0.1)
				(type default)
			)
			(layer "F.Fab")
		)
		(fp_line
			(start 0.120396 0.3048)
			(end 0.120396 0.2794)
			(stroke
				(width 0.1)
				(type default)
			)
			(layer "F.Fab")
		)
		(fp_line
			(start 0.120396 0.2794)
			(end -0.12065 0.2794)
			(stroke
				(width 0.1)
				(type default)
			)
			(layer "F.Fab")
		)
		(fp_line
			(start -0.12065 0.3048)
			(end -0.67945 0.3048)
			(stroke
				(width 0.1)
				(type default)
			)
			(layer "F.Fab")
		)
		(fp_line
			(start -0.12065 0.2794)
			(end -0.12065 0.3048)
			(stroke
				(width 0.1)
				(type default)
			)
			(layer "F.Fab")
		)
		(fp_line
			(start -0.12065 -0.2794)
			(end 0.12065 -0.2794)
			(stroke
				(width 0.1)
				(type default)
			)
			(layer "F.Fab")
		)
		(fp_line
			(start -0.12065 -0.305054)
			(end -0.12065 -0.2794)
			(stroke
				(width 0.1)
				(type default)
			)
			(layer "F.Fab")
		)
		(fp_line
			(start -0.67945 0.3048)
			(end -0.67945 -0.305054)
			(stroke
				(width 0.1)
				(type default)
			)
			(layer "F.Fab")
		)
		(fp_line
			(start -0.67945 -0.305054)
			(end -0.12065 -0.305054)
			(stroke
				(width 0.1)
				(type default)
			)
			(layer "F.Fab")
		)
		(pad "1" smd circle
			(at -0.40005 0 180)
			(size 0 0)
			(layers "F.Cu" "F.Mask" "F.Paste")
			(net "FAN_7_OK_LED")
		)
		(pad "2" smd circle
			(at 0.40005 0 180)
			(size 0 0)
			(layers "F.Cu" "F.Mask" "F.Paste")
			(net "FAN_7_OK_R_LED")
		)
	)
	(footprint ""
		(layer "F.Cu")
		(at 11.176 -4.445)
		(property "Reference" "H13"
			(at -1.037844 -3.339338 0)
			(unlocked yes)
			(layer "F.SilkS")
			(effects
				(font
					(size 0.7874 0.5842)
					(thickness 0.1524)
				)
				(justify left)
			)
		)
		(property "Value" ""
			(at 0 0 0)
			(layer "F.Fab")
			(effects
				(font
					(size 1.27 1.27)
				)
			)
		)
		(duplicate_pad_numbers_are_jumpers no)
		(fp_circle
			(center 0 0)
			(end 2.4003 0)
			(stroke
				(width 0.1524)
				(type default)
			)
			(fill no)
			(layer "F.SilkS")
		)
		(fp_circle
			(center 0 0)
			(end 6.5913 0)
			(stroke
				(width 0.1524)
				(type default)
			)
			(fill no)
			(layer "B.SilkS")
		)
		(fp_circle
			(center 0 0)
			(end 6.5913 0)
			(stroke
				(width 0.1)
				(type default)
			)
			(fill no)
			(layer "B.Fab")
		)
		(fp_circle
			(center 0 0)
			(end 2.4003 0)
			(stroke
				(width 0.1)
				(type default)
			)
			(fill no)
			(layer "F.Fab")
		)
		(pad "" np_thru_hole circle
			(at 0 0)
			(size 3.175 3.175)
			(drill 3.175)
			(layers "*.Cu" "*.Mask")
			(clearance 0.381)
			(thermal_gap 0.381)
		)
		(zone
			(layers "F.Cu" "B.Cu" "In1.Cu" "In2.Cu" "In3.Cu" "In4.Cu")
			(hatch none 0.5)
			(connect_pads
				(clearance 0)
			)
			(min_thickness 0.25)
			(keepout
				(tracks not_allowed)
				(vias allowed)
				(pads allowed)
				(copperpour not_allowed)
				(footprints allowed)
			)
			(placement
				(enabled no)
				(sheetname "")
			)
			(fill
				(thermal_gap 0.5)
				(thermal_bridge_width 0.5)
				(island_removal_mode 0)
			)
			(polygon
				(pts
					(arc
						(start 13.2715 -4.445)
						(mid 9.0805 -4.445)
						(end 13.2715 -4.445)
					)
				)
			)
		)
	)
	(footprint ""
		(layer "F.Cu")
		(at 39.206932 -256.413)
		(property "Reference" "C2064"
			(at 0 0 0)
			(layer "F.SilkS")
			(hide yes)
			(effects
				(font
					(size 1.27 1.27)
				)
			)
		)
		(property "Value" ""
			(at 0 0 0)
			(layer "F.Fab")
			(effects
				(font
					(size 1.27 1.27)
				)
			)
		)
		(duplicate_pad_numbers_are_jumpers no)
		(fp_line
			(start -0.7874 -0.4064)
			(end 0.7874 -0.4064)
			(stroke
				(width 0.1524)
				(type default)
			)
			(layer "F.SilkS")
		)
		(fp_line
			(start -0.7874 0.4064)
			(end -0.7874 -0.4064)
			(stroke
				(width 0.1524)
				(type default)
			)
			(layer "F.SilkS")
		)
		(fp_line
			(start 0.7874 -0.4064)
			(end 0.7874 0.4064)
			(stroke
				(width 0.1524)
				(type default)
			)
			(layer "F.SilkS")
		)
		(fp_line
			(start 0.7874 0.4064)
			(end -0.7874 0.4064)
			(stroke
				(width 0.1524)
				(type default)
			)
			(layer "F.SilkS")
		)
		(fp_line
			(start -0.67945 -0.305054)
			(end -0.12065 -0.305054)
			(stroke
				(width 0.1)
				(type default)
			)
			(layer "F.Fab")
		)
		(fp_line
			(start -0.67945 0.3048)
			(end -0.67945 -0.305054)
			(stroke
				(width 0.1)
				(type default)
			)
			(layer "F.Fab")
		)
		(fp_line
			(start -0.12065 -0.305054)
			(end -0.12065 -0.2794)
			(stroke
				(width 0.1)
				(type default)
			)
			(layer "F.Fab")
		)
		(fp_line
			(start -0.12065 -0.2794)
			(end 0.12065 -0.2794)
			(stroke
				(width 0.1)
				(type default)
			)
			(layer "F.Fab")
		)
		(fp_line
			(start -0.12065 0.2794)
			(end -0.12065 0.3048)
			(stroke
				(width 0.1)
				(type default)
			)
			(layer "F.Fab")
		)
		(fp_line
			(start -0.12065 0.3048)
			(end -0.67945 0.3048)
			(stroke
				(width 0.1)
				(type default)
			)
			(layer "F.Fab")
		)
		(fp_line
			(start 0.120396 0.2794)
			(end -0.12065 0.2794)
			(stroke
				(width 0.1)
				(type default)
			)
			(layer "F.Fab")
		)
		(fp_line
			(start 0.120396 0.3048)
			(end 0.120396 0.2794)
			(stroke
				(width 0.1)
				(type default)
			)
			(layer "F.Fab")
		)
		(fp_line
			(start 0.12065 -0.3048)
			(end 0.67945 -0.3048)
			(stroke
				(width 0.1)
				(type default)
			)
			(layer "F.Fab")
		)
		(fp_line
			(start 0.12065 -0.2794)
			(end 0.12065 -0.3048)
			(stroke
				(width 0.1)
				(type default)
			)
			(layer "F.Fab")
		)
		(fp_line
			(start 0.67945 -0.3048)
			(end 0.67945 0.3048)
			(stroke
				(width 0.1)
				(type default)
			)
			(layer "F.Fab")
		)
		(fp_line
			(start 0.67945 0.3048)
			(end 0.120396 0.3048)
			(stroke
				(width 0.1)
				(type default)
			)
			(layer "F.Fab")
		)
		(pad "1" smd circle
			(at -0.40005 0)
			(size 0 0)
			(layers "F.Cu" "F.Mask" "F.Paste")
			(net "P3V3_AUX")
		)
		(pad "2" smd circle
			(at 0.40005 0)
			(size 0 0)
			(layers "F.Cu" "F.Mask" "F.Paste")
			(net "GND")
		)
	)
)
